# BASEBOARD_FAB2 (Tioga Pass) — schematic netlist excerpt (pin names and nets, part order shuffled) for the footprints in the layout excerpt that follows; sources: Cadence DE-HDL packaged netlist, KiCad conversion of Wiwynn_Tioga_Pass_MB.brd

C3L21  CAPP  470UF 2V 20% ALUM  pkg SM  page 236 : A = PVNN_PCH_STBY ; B = GND
CT2  CAP  1000PF 50V 10% X7R  pkg 0402LF  page 202 : A = A_TSENSE_PVCCIN_CPU0 ; B = GND
C5L9  CAP_A  47UF 4V 20% X5R  pkg 0603V  page 220 : A = PVDDQ_DEF ; B = GND

(kicad_pcb
	(version 20260206)
	(generator "pcbnew")
	(generator_version "10.0")
	(general
		(thickness 1.6)
		(legacy_teardrops no)
	)
	(paper "A4")
	(title_block
		(title "Wiwynn_Tioga_Pass_MB.brd")
		(comment 1 "Tioga Pass / footprints 4291-4293 of 4770")
	)
	(layers
		(0 "F.Cu" signal "TOP")
		(4 "In1.Cu" signal "L2GND")
		(6 "In2.Cu" signal "L3")
		(8 "In3.Cu" signal "L4GND")
		(10 "In4.Cu" signal "L5")
		(12 "In5.Cu" signal "L6GND")
		(14 "In6.Cu" signal "L7VCC")
		(16 "In7.Cu" signal "L8VCC")
		(18 "In8.Cu" signal "L9GND")
		(20 "In9.Cu" signal "L10")
		(22 "In10.Cu" signal "L11GND")
		(24 "In11.Cu" signal "L12")
		(26 "In12.Cu" signal "L13GND")
		(2 "B.Cu" signal "BOTTOM")
		(9 "F.Adhes" user "F.Adhesive")
		(11 "B.Adhes" user "B.Adhesive")
		(13 "F.Paste" user "Package Geometry/Pastemask Top")
		(15 "B.Paste" user "Package Geometry/Pastemask Bottom")
		(5 "F.SilkS" user "Ref Des/Silkscreen Top")
		(7 "B.SilkS" user "Ref Des/Silkscreen Bottom")
		(1 "F.Mask" user "Board Geometry/Soldermask Top")
		(3 "B.Mask" user "Board Geometry/Soldermask Bottom")
		(17 "Dwgs.User" user "User.Drawings")
		(19 "Cmts.User" user "User.Comments")
		(21 "Eco1.User" user "User.Eco1")
		(23 "Eco2.User" user "User.Eco2")
		(25 "Edge.Cuts" user "Board Geometry/Outline")
		(27 "Margin" user)
		(31 "F.CrtYd" user "Package Geometry/Place Bound Top")
		(29 "B.CrtYd" user "Package Geometry/Place Bound Bottom")
		(35 "F.Fab" user "Ref Des/Assembly Top")
		(33 "B.Fab" user "Ref Des/Assembly Bottom")
	)
	(footprint ""
		(layer "B.Cu")
		(at 266.397232 -145.0086 90)
		(property "Reference" "C5L9"
			(at -1.848866 0.752348 90)
			(unlocked yes)
			(layer "B.SilkS")
			(effects
				(font
					(size 1.27 0.9652)
					(thickness 0.1524)
				)
				(justify mirror)
			)
		)
		(property "Value" ""
			(at 0 0 90)
			(layer "B.Fab")
			(effects
				(font
					(size 1.27 1.27)
				)
				(justify mirror)
			)
		)
		(duplicate_pad_numbers_are_jumpers no)
		(fp_rect
			(start 0.500126 1.598422)
			(end -0.500126 -0.201422)
			(stroke
				(width 0)
				(type default)
			)
			(fill no)
			(layer "B.CrtYd")
		)
		(fp_line
			(start 0.500126 -0.201422)
			(end -0.500126 -0.201422)
			(stroke
				(width 0.1)
				(type default)
			)
			(layer "B.Fab")
		)
		(fp_line
			(start -0.500126 -0.201422)
			(end -0.500126 1.598422)
			(stroke
				(width 0.1)
				(type default)
			)
			(layer "B.Fab")
		)
		(fp_line
			(start 0.500126 1.598422)
			(end 0.500126 -0.201422)
			(stroke
				(width 0.1)
				(type default)
			)
			(layer "B.Fab")
		)
		(fp_line
			(start -0.500126 1.598422)
			(end 0.500126 1.598422)
			(stroke
				(width 0.1)
				(type default)
			)
			(layer "B.Fab")
		)
		(pad "1" smd rect
			(at 0 0)
			(size 0.889 0.9906)
			(layers "B.Cu" "B.Mask" "B.Paste")
			(net "PVDDQ_DEF")
		)
		(pad "2" smd rect
			(at 0 1.397)
			(size 0.889 0.9906)
			(layers "B.Cu" "B.Mask" "B.Paste")
			(net "GND")
		)
		(zone
			(layer "B.Cu")
			(hatch none 0.5)
			(connect_pads
				(clearance 0)
			)
			(min_thickness 0.25)
			(keepout
				(tracks not_allowed)
				(vias allowed)
				(pads allowed)
				(copperpour not_allowed)
				(footprints allowed)
			)
			(placement
				(enabled no)
				(sheetname "")
			)
			(fill
				(thermal_gap 0.5)
				(thermal_bridge_width 0.5)
				(island_removal_mode 0)
			)
			(polygon
				(pts
					(xy 267.349732 -145.5039) (xy 266.841732 -145.5039) (xy 266.841732 -144.5133) (xy 267.349732 -144.5133)
				)
			)
		)
		(zone
			(layer "B.Cu")
			(hatch none 0.5)
			(connect_pads
				(clearance 0)
			)
			(min_thickness 0.25)
			(keepout
				(tracks allowed)
				(vias not_allowed)
				(pads allowed)
				(copperpour not_allowed)
				(footprints allowed)
			)
			(placement
				(enabled no)
				(sheetname "")
			)
			(fill
				(thermal_gap 0.5)
				(thermal_bridge_width 0.5)
				(island_removal_mode 0)
			)
			(polygon
				(pts
					(xy 267.349732 -145.5039) (xy 266.841732 -145.5039) (xy 266.841732 -144.5133) (xy 267.349732 -144.5133)
				)
			)
		)
	)
	(footprint ""
		(layer "B.Cu")
		(at 195.2244 -55.88 90)
		(property "Reference" "CT2"
			(at 0.8382 -0.84963 90)
			(unlocked yes)
			(layer "B.SilkS")
			(effects
				(font
					(size 0.7874 0.5842)
					(thickness 0.1524)
				)
				(justify left mirror)
			)
		)
		(property "Value" ""
			(at 0 0 90)
			(layer "B.Fab")
			(effects
				(font
					(size 1.27 1.27)
				)
				(justify mirror)
			)
		)
		(duplicate_pad_numbers_are_jumpers no)
		(fp_poly
			(pts
				(xy -0.3048 -0.1016) (xy -0.3048 0.9906) (xy 0.3048 0.9906) (xy 0.3048 -0.1016)
			)
			(stroke
				(width 0)
				(type default)
			)
			(fill no)
			(layer "B.CrtYd")
		)
		(fp_line
			(start 0.3048 -0.1016)
			(end 0.3048 0.9906)
			(stroke
				(width 0.1)
				(type default)
			)
			(layer "B.Fab")
		)
		(fp_line
			(start -0.3048 -0.1016)
			(end 0.3048 -0.1016)
			(stroke
				(width 0.1)
				(type default)
			)
			(layer "B.Fab")
		)
		(fp_line
			(start 0.3048 0.9906)
			(end -0.3048 0.9906)
			(stroke
				(width 0.1)
				(type default)
			)
			(layer "B.Fab")
		)
		(fp_line
			(start -0.3048 0.9906)
			(end -0.3048 -0.1016)
			(stroke
				(width 0.1)
				(type default)
			)
			(layer "B.Fab")
		)
		(pad "1" smd rect
			(at 0 0 270)
			(size 0.508 0.508)
			(layers "B.Cu" "B.Mask" "B.Paste")
			(net "A_TSENSE_PVCCIN_CPU0")
		)
		(pad "2" smd rect
			(at 0 0.889 270)
			(size 0.508 0.508)
			(layers "B.Cu" "B.Mask" "B.Paste")
			(net "GND")
		)
		(zone
			(layer "B.Cu")
			(hatch none 0.5)
			(connect_pads
				(clearance 0)
			)
			(min_thickness 0.25)
			(keepout
				(tracks allowed)
				(vias not_allowed)
				(pads allowed)
				(copperpour not_allowed)
				(footprints allowed)
			)
			(placement
				(enabled no)
				(sheetname "")
			)
			(fill
				(thermal_gap 0.5)
				(thermal_bridge_width 0.5)
				(island_removal_mode 0)
			)
			(polygon
				(pts
					(xy 195.4784 -56.134) (xy 195.4784 -55.626) (xy 195.8594 -55.626) (xy 195.8594 -56.134)
				)
			)
		)
		(zone
			(layer "B.Cu")
			(hatch none 0.5)
			(connect_pads
				(clearance 0)
			)
			(min_thickness 0.25)
			(keepout
				(tracks not_allowed)
				(vias allowed)
				(pads allowed)
				(copperpour not_allowed)
				(footprints allowed)
			)
			(placement
				(enabled no)
				(sheetname "")
			)
			(fill
				(thermal_gap 0.5)
				(thermal_bridge_width 0.5)
				(island_removal_mode 0)
			)
			(polygon
				(pts
					(xy 195.8594 -56.134) (xy 195.8594 -55.626) (xy 195.4784 -55.626) (xy 195.4784 -56.134)
				)
			)
		)
	)
	(footprint ""
		(layer "B.Cu")
		(at 374.777 -140.589 180)
		(property "Reference" "C3L21"
			(at -3.10007 3.24612 270)
			(unlocked yes)
			(layer "B.SilkS")
			(effects
				(font
					(size 0.7874 0.5842)
					(thickness 0.1524)
				)
				(justify mirror)
			)
		)
		(property "Value" ""
			(at 0 0 0)
			(layer "B.Fab")
			(effects
				(font
					(size 1.27 1.27)
				)
				(justify mirror)
			)
		)
		(duplicate_pad_numbers_are_jumpers no)
		(fp_line
			(start 2.563114 1.633728)
			(end 1.6002 1.633728)
			(stroke
				(width 0.1524)
				(type default)
			)
			(layer "B.SilkS")
		)
		(fp_line
			(start 2.563114 -1.616456)
			(end 2.563114 1.633728)
			(stroke
				(width 0.1524)
				(type default)
			)
			(layer "B.SilkS")
		)
		(fp_line
			(start 2.286 7.366)
			(end 2.286 1.632712)
			(stroke
				(width 0.1524)
				(type default)
			)
			(layer "B.SilkS")
		)
		(fp_line
			(start 2.286 7.366)
			(end 1.60147 7.366)
			(stroke
				(width 0.1524)
				(type default)
			)
			(layer "B.SilkS")
		)
		(fp_line
			(start 1.6002 -1.616456)
			(end 2.563114 -1.616456)
			(stroke
				(width 0.1524)
				(type default)
			)
			(layer "B.SilkS")
		)
		(fp_line
			(start -1.6002 -1.616456)
			(end -2.504948 -1.616456)
			(stroke
				(width 0.1524)
				(type default)
			)
			(layer "B.SilkS")
		)
		(fp_line
			(start -2.286 7.366)
			(end -1.600708 7.366)
			(stroke
				(width 0.1524)
				(type default)
			)
			(layer "B.SilkS")
		)
		(fp_line
			(start -2.286 7.366)
			(end -2.286 1.63195)
			(stroke
				(width 0.1524)
				(type default)
			)
			(layer "B.SilkS")
		)
		(fp_line
			(start -2.504948 1.633728)
			(end -1.6002 1.633728)
			(stroke
				(width 0.1524)
				(type default)
			)
			(layer "B.SilkS")
		)
		(fp_line
			(start -2.504948 -1.616456)
			(end -2.504948 1.633728)
			(stroke
				(width 0.1524)
				(type default)
			)
			(layer "B.SilkS")
		)
		(fp_rect
			(start 2.286 7.366)
			(end -2.286 -0.254)
			(stroke
				(width 0)
				(type default)
			)
			(fill no)
			(layer "B.CrtYd")
		)
		(fp_line
			(start 2.286 7.366)
			(end 2.286 -0.254)
			(stroke
				(width 0.1)
				(type default)
			)
			(layer "B.Fab")
		)
		(fp_line
			(start 2.286 -0.254)
			(end -2.286 -0.254)
			(stroke
				(width 0.1)
				(type default)
			)
			(layer "B.Fab")
		)
		(fp_line
			(start -2.286 7.366)
			(end 2.286 7.366)
			(stroke
				(width 0.1)
				(type default)
			)
			(layer "B.Fab")
		)
		(fp_line
			(start -2.286 -0.254)
			(end -2.286 7.366)
			(stroke
				(width 0.1)
				(type default)
			)
			(layer "B.Fab")
		)
		(pad "1" smd rect
			(at 0 0)
			(size 2.54 3.048)
			(layers "B.Cu" "B.Mask" "B.Paste")
			(net "PVNN_PCH_STBY")
		)
		(pad "2" smd rect
			(at 0 7.112)
			(size 2.54 3.048)
			(layers "B.Cu" "B.Mask" "B.Paste")
			(net "GND")
		)
	)
)
